(kicad_pcb
	(version 20260206)
	(generator "pcbnew")
	(generator_version "10.0")
	(general
		(thickness 1.6)
		(legacy_teardrops no)
	)
	(paper "A4")
	(title_block
		(title "01162023_DA0F0TEBIF0_F0T_Expander_BD_F_brd_V02_OCP.brd")
		(comment 1 "Grand Teton / footprints 291-295 of 9728")
	)
	(layers
		(0 "F.Cu" signal "TOP")
		(4 "In1.Cu" signal "GND")
		(6 "In2.Cu" signal "VCC")
		(8 "In3.Cu" signal "VCC1")
		(10 "In4.Cu" signal "GND1")
		(12 "In5.Cu" signal "IN1")
		(14 "In6.Cu" signal "GND2")
		(16 "In7.Cu" signal "IN2")
		(18 "In8.Cu" signal "GND3")
		(20 "In9.Cu" signal "IN3")
		(22 "In10.Cu" signal "GND4")
		(24 "In11.Cu" signal "IN4")
		(26 "In12.Cu" signal "GND5")
		(28 "In13.Cu" signal "IN5")
		(30 "In14.Cu" signal "GND6")
		(32 "In15.Cu" signal "IN6")
		(34 "In16.Cu" signal "GND7")
		(2 "B.Cu" signal "BOTTOM")
		(9 "F.Adhes" user "F.Adhesive")
		(11 "B.Adhes" user "B.Adhesive")
		(13 "F.Paste" user "Package Geometry/Pastemask Top")
		(15 "B.Paste" user "Package Geometry/Pastemask Bottom")
		(5 "F.SilkS" user "Ref Des/Silkscreen Top")
		(7 "B.SilkS" user "Ref Des/Silkscreen Bottom")
		(1 "F.Mask" user "Board Geometry/Soldermask Top")
		(3 "B.Mask" user "Board Geometry/Soldermask Bottom")
		(17 "Dwgs.User" user "User.Drawings")
		(19 "Cmts.User" user "User.Comments")
		(21 "Eco1.User" user "User.Eco1")
		(23 "Eco2.User" user "User.Eco2")
		(25 "Edge.Cuts" user "Board Geometry/Outline")
		(27 "Margin" user)
		(31 "F.CrtYd" user "Package Geometry/Place Bound Top")
		(29 "B.CrtYd" user "Package Geometry/Place Bound Bottom")
		(35 "F.Fab" user "Ref Des/Assembly Top")
		(33 "B.Fab" user "Ref Des/Assembly Bottom")
	)
	(footprint ""
		(layer "F.Cu")
		(at 21.290026 -72.766682 90)
		(property "Reference" "PR6905"
			(at 0 0 90)
			(layer "F.SilkS")
			(hide yes)
			(effects
				(font
					(size 1.27 1.27)
				)
			)
		)
		(property "Value" ""
			(at 0 0 90)
			(layer "F.Fab")
			(effects
				(font
					(size 1.27 1.27)
				)
			)
		)
		(duplicate_pad_numbers_are_jumpers no)
		(fp_line
			(start 0.7874 -0.4064)
			(end 0.7874 0.4064)
			(stroke
				(width 0.1524)
				(type default)
			)
			(layer "F.SilkS")
		)
		(fp_line
			(start -0.7874 -0.4064)
			(end 0.7874 -0.4064)
			(stroke
				(width 0.1524)
				(type default)
			)
			(layer "F.SilkS")
		)
		(fp_line
			(start 0.7874 0.4064)
			(end -0.7874 0.4064)
			(stroke
				(width 0.1524)
				(type default)
			)
			(layer "F.SilkS")
		)
		(fp_line
			(start -0.7874 0.4064)
			(end -0.7874 -0.4064)
			(stroke
				(width 0.1524)
				(type default)
			)
			(layer "F.SilkS")
		)
		(fp_line
			(start -0.12065 -0.305054)
			(end -0.12065 -0.2794)
			(stroke
				(width 0.1)
				(type default)
			)
			(layer "F.Fab")
		)
		(fp_line
			(start -0.67945 -0.305054)
			(end -0.12065 -0.305054)
			(stroke
				(width 0.1)
				(type default)
			)
			(layer "F.Fab")
		)
		(fp_line
			(start 0.67945 -0.3048)
			(end 0.67945 0.3048)
			(stroke
				(width 0.1)
				(type default)
			)
			(layer "F.Fab")
		)
		(fp_line
			(start 0.12065 -0.3048)
			(end 0.67945 -0.3048)
			(stroke
				(width 0.1)
				(type default)
			)
			(layer "F.Fab")
		)
		(fp_line
			(start 0.12065 -0.2794)
			(end 0.12065 -0.3048)
			(stroke
				(width 0.1)
				(type default)
			)
			(layer "F.Fab")
		)
		(fp_line
			(start -0.12065 -0.2794)
			(end 0.12065 -0.2794)
			(stroke
				(width 0.1)
				(type default)
			)
			(layer "F.Fab")
		)
		(fp_line
			(start 0.120396 0.2794)
			(end -0.12065 0.2794)
			(stroke
				(width 0.1)
				(type default)
			)
			(layer "F.Fab")
		)
		(fp_line
			(start -0.12065 0.2794)
			(end -0.12065 0.3048)
			(stroke
				(width 0.1)
				(type default)
			)
			(layer "F.Fab")
		)
		(fp_line
			(start 0.67945 0.3048)
			(end 0.120396 0.3048)
			(stroke
				(width 0.1)
				(type default)
			)
			(layer "F.Fab")
		)
		(fp_line
			(start 0.120396 0.3048)
			(end 0.120396 0.2794)
			(stroke
				(width 0.1)
				(type default)
			)
			(layer "F.Fab")
		)
		(fp_line
			(start -0.12065 0.3048)
			(end -0.67945 0.3048)
			(stroke
				(width 0.1)
				(type default)
			)
			(layer "F.Fab")
		)
		(fp_line
			(start -0.67945 0.3048)
			(end -0.67945 -0.305054)
			(stroke
				(width 0.1)
				(type default)
			)
			(layer "F.Fab")
		)
		(pad "1" smd circle
			(at -0.40005 0 90)
			(size 0 0)
			(layers "F.Cu" "F.Mask" "F.Paste")
			(net "P12V_SSD0_CO_ILIMIT")
		)
		(pad "2" smd circle
			(at 0.40005 0 90)
			(size 0 0)
			(layers "F.Cu" "F.Mask" "F.Paste")
			(net "GND")
		)
	)
	(footprint ""
		(layer "F.Cu")
		(at 224.851976 -375.122186)
		(property "Reference" "PR37"
			(at 0 0 0)
			(layer "F.SilkS")
			(hide yes)
			(effects
				(font
					(size 1.27 1.27)
				)
			)
		)
		(property "Value" ""
			(at 0 0 0)
			(layer "F.Fab")
			(effects
				(font
					(size 1.27 1.27)
				)
			)
		)
		(duplicate_pad_numbers_are_jumpers no)
		(fp_line
			(start -0.7874 -0.4064)
			(end 0.7874 -0.4064)
			(stroke
				(width 0.1524)
				(type default)
			)
			(layer "F.SilkS")
		)
		(fp_line
			(start -0.7874 0.4064)
			(end -0.7874 -0.4064)
			(stroke
				(width 0.1524)
				(type default)
			)
			(layer "F.SilkS")
		)
		(fp_line
			(start 0.7874 -0.4064)
			(end 0.7874 0.4064)
			(stroke
				(width 0.1524)
				(type default)
			)
			(layer "F.SilkS")
		)
		(fp_line
			(start 0.7874 0.4064)
			(end -0.7874 0.4064)
			(stroke
				(width 0.1524)
				(type default)
			)
			(layer "F.SilkS")
		)
		(fp_line
			(start -0.67945 -0.305054)
			(end -0.12065 -0.305054)
			(stroke
				(width 0.1)
				(type default)
			)
			(layer "F.Fab")
		)
		(fp_line
			(start -0.67945 0.3048)
			(end -0.67945 -0.305054)
			(stroke
				(width 0.1)
				(type default)
			)
			(layer "F.Fab")
		)
		(fp_line
			(start -0.12065 -0.305054)
			(end -0.12065 -0.2794)
			(stroke
				(width 0.1)
				(type default)
			)
			(layer "F.Fab")
		)
		(fp_line
			(start -0.12065 -0.2794)
			(end 0.12065 -0.2794)
			(stroke
				(width 0.1)
				(type default)
			)
			(layer "F.Fab")
		)
		(fp_line
			(start -0.12065 0.2794)
			(end -0.12065 0.3048)
			(stroke
				(width 0.1)
				(type default)
			)
			(layer "F.Fab")
		)
		(fp_line
			(start -0.12065 0.3048)
			(end -0.67945 0.3048)
			(stroke
				(width 0.1)
				(type default)
			)
			(layer "F.Fab")
		)
		(fp_line
			(start 0.120396 0.2794)
			(end -0.12065 0.2794)
			(stroke
				(width 0.1)
				(type default)
			)
			(layer "F.Fab")
		)
		(fp_line
			(start 0.120396 0.3048)
			(end 0.120396 0.2794)
			(stroke
				(width 0.1)
				(type default)
			)
			(layer "F.Fab")
		)
		(fp_line
			(start 0.12065 -0.3048)
			(end 0.67945 -0.3048)
			(stroke
				(width 0.1)
				(type default)
			)
			(layer "F.Fab")
		)
		(fp_line
			(start 0.12065 -0.2794)
			(end 0.12065 -0.3048)
			(stroke
				(width 0.1)
				(type default)
			)
			(layer "F.Fab")
		)
		(fp_line
			(start 0.67945 -0.3048)
			(end 0.67945 0.3048)
			(stroke
				(width 0.1)
				(type default)
			)
			(layer "F.Fab")
		)
		(fp_line
			(start 0.67945 0.3048)
			(end 0.120396 0.3048)
			(stroke
				(width 0.1)
				(type default)
			)
			(layer "F.Fab")
		)
		(pad "1" smd circle
			(at -0.40005 0)
			(size 0 0)
			(layers "F.Cu" "F.Mask" "F.Paste")
			(net "HSC_SCREF")
		)
		(pad "2" smd circle
			(at 0.40005 0)
			(size 0 0)
			(layers "F.Cu" "F.Mask" "F.Paste")
			(net "HSC_SCREF_2")
		)
	)
	(footprint ""
		(layer "F.Cu")
		(at 244.447314 -274.768056 180)
		(property "Reference" "R799"
			(at 0 0 180)
			(layer "F.SilkS")
			(hide yes)
			(effects
				(font
					(size 1.27 1.27)
				)
			)
		)
		(property "Value" ""
			(at 0 0 180)
			(layer "F.Fab")
			(effects
				(font
					(size 1.27 1.27)
				)
			)
		)
		(duplicate_pad_numbers_are_jumpers no)
		(fp_line
			(start 0.7874 0.4064)
			(end -0.7874 0.4064)
			(stroke
				(width 0.1524)
				(type default)
			)
			(layer "F.SilkS")
		)
		(fp_line
			(start 0.7874 -0.4064)
			(end 0.7874 0.4064)
			(stroke
				(width 0.1524)
				(type default)
			)
			(layer "F.SilkS")
		)
		(fp_line
			(start -0.7874 0.4064)
			(end -0.7874 -0.4064)
			(stroke
				(width 0.1524)
				(type default)
			)
			(layer "F.SilkS")
		)
		(fp_line
			(start -0.7874 -0.4064)
			(end 0.7874 -0.4064)
			(stroke
				(width 0.1524)
				(type default)
			)
			(layer "F.SilkS")
		)
		(fp_line
			(start 0.67945 0.3048)
			(end 0.120396 0.3048)
			(stroke
				(width 0.1)
				(type default)
			)
			(layer "F.Fab")
		)
		(fp_line
			(start 0.67945 -0.3048)
			(end 0.67945 0.3048)
			(stroke
				(width 0.1)
				(type default)
			)
			(layer "F.Fab")
		)
		(fp_line
			(start 0.12065 -0.2794)
			(end 0.12065 -0.3048)
			(stroke
				(width 0.1)
				(type default)
			)
			(layer "F.Fab")
		)
		(fp_line
			(start 0.12065 -0.3048)
			(end 0.67945 -0.3048)
			(stroke
				(width 0.1)
				(type default)
			)
			(layer "F.Fab")
		)
		(fp_line
			(start 0.120396 0.3048)
			(end 0.120396 0.2794)
			(stroke
				(width 0.1)
				(type default)
			)
			(layer "F.Fab")
		)
		(fp_line
			(start 0.120396 0.2794)
			(end -0.12065 0.2794)
			(stroke
				(width 0.1)
				(type default)
			)
			(layer "F.Fab")
		)
		(fp_line
			(start -0.12065 0.3048)
			(end -0.67945 0.3048)
			(stroke
				(width 0.1)
				(type default)
			)
			(layer "F.Fab")
		)
		(fp_line
			(start -0.12065 0.2794)
			(end -0.12065 0.3048)
			(stroke
				(width 0.1)
				(type default)
			)
			(layer "F.Fab")
		)
		(fp_line
			(start -0.12065 -0.2794)
			(end 0.12065 -0.2794)
			(stroke
				(width 0.1)
				(type default)
			)
			(layer "F.Fab")
		)
		(fp_line
			(start -0.12065 -0.305054)
			(end -0.12065 -0.2794)
			(stroke
				(width 0.1)
				(type default)
			)
			(layer "F.Fab")
		)
		(fp_line
			(start -0.67945 0.3048)
			(end -0.67945 -0.305054)
			(stroke
				(width 0.1)
				(type default)
			)
			(layer "F.Fab")
		)
		(fp_line
			(start -0.67945 -0.305054)
			(end -0.12065 -0.305054)
			(stroke
				(width 0.1)
				(type default)
			)
			(layer "F.Fab")
		)
		(pad "1" smd circle
			(at -0.40005 0 180)
			(size 0 0)
			(layers "F.Cu" "F.Mask" "F.Paste")
			(net "P1V25_PEX2_R")
		)
		(pad "2" smd circle
			(at 0.40005 0 180)
			(size 0 0)
			(layers "F.Cu" "F.Mask" "F.Paste")
			(net "P12V_PEX2_P1V25_VIN_P")
		)
	)
	(footprint ""
		(layer "F.Cu")
		(at 250.309888 -279.476708 180)
		(property "Reference" "PR6617"
			(at 0 0 180)
			(layer "F.SilkS")
			(hide yes)
			(effects
				(font
					(size 1.27 1.27)
				)
			)
		)
		(property "Value" ""
			(at 0 0 180)
			(layer "F.Fab")
			(effects
				(font
					(size 1.27 1.27)
				)
			)
		)
		(duplicate_pad_numbers_are_jumpers no)
		(fp_line
			(start 0.7874 0.4064)
			(end -0.7874 0.4064)
			(stroke
				(width 0.1524)
				(type default)
			)
			(layer "F.SilkS")
		)
		(fp_line
			(start 0.7874 -0.4064)
			(end 0.7874 0.4064)
			(stroke
				(width 0.1524)
				(type default)
			)
			(layer "F.SilkS")
		)
		(fp_line
			(start -0.7874 0.4064)
			(end -0.7874 -0.4064)
			(stroke
				(width 0.1524)
				(type default)
			)
			(layer "F.SilkS")
		)
		(fp_line
			(start -0.7874 -0.4064)
			(end 0.7874 -0.4064)
			(stroke
				(width 0.1524)
				(type default)
			)
			(layer "F.SilkS")
		)
		(fp_line
			(start 0.67945 0.3048)
			(end 0.120396 0.3048)
			(stroke
				(width 0.1)
				(type default)
			)
			(layer "F.Fab")
		)
		(fp_line
			(start 0.67945 -0.3048)
			(end 0.67945 0.3048)
			(stroke
				(width 0.1)
				(type default)
			)
			(layer "F.Fab")
		)
		(fp_line
			(start 0.12065 -0.2794)
			(end 0.12065 -0.3048)
			(stroke
				(width 0.1)
				(type default)
			)
			(layer "F.Fab")
		)
		(fp_line
			(start 0.12065 -0.3048)
			(end 0.67945 -0.3048)
			(stroke
				(width 0.1)
				(type default)
			)
			(layer "F.Fab")
		)
		(fp_line
			(start 0.120396 0.3048)
			(end 0.120396 0.2794)
			(stroke
				(width 0.1)
				(type default)
			)
			(layer "F.Fab")
		)
		(fp_line
			(start 0.120396 0.2794)
			(end -0.12065 0.2794)
			(stroke
				(width 0.1)
				(type default)
			)
			(layer "F.Fab")
		)
		(fp_line
			(start -0.12065 0.3048)
			(end -0.67945 0.3048)
			(stroke
				(width 0.1)
				(type default)
			)
			(layer "F.Fab")
		)
		(fp_line
			(start -0.12065 0.2794)
			(end -0.12065 0.3048)
			(stroke
				(width 0.1)
				(type default)
			)
			(layer "F.Fab")
		)
		(fp_line
			(start -0.12065 -0.2794)
			(end 0.12065 -0.2794)
			(stroke
				(width 0.1)
				(type default)
			)
			(layer "F.Fab")
		)
		(fp_line
			(start -0.12065 -0.305054)
			(end -0.12065 -0.2794)
			(stroke
				(width 0.1)
				(type default)
			)
			(layer "F.Fab")
		)
		(fp_line
			(start -0.67945 0.3048)
			(end -0.67945 -0.305054)
			(stroke
				(width 0.1)
				(type default)
			)
			(layer "F.Fab")
		)
		(fp_line
			(start -0.67945 -0.305054)
			(end -0.12065 -0.305054)
			(stroke
				(width 0.1)
				(type default)
			)
			(layer "F.Fab")
		)
		(pad "1" smd circle
			(at -0.40005 0 180)
			(size 0 0)
			(layers "F.Cu" "F.Mask" "F.Paste")
			(net "SMB_LTC4282_TEMP_SDA")
		)
		(pad "2" smd circle
			(at 0.40005 0 180)
			(size 0 0)
			(layers "F.Cu" "F.Mask" "F.Paste")
			(net "SMB_BIC_I2C6_MUX_PEX_ADC_R_SDA")
		)
	)
	(footprint ""
		(layer "F.Cu")
		(at 79.314802 -81.36001 -90)
		(property "Reference" "R102"
			(at 0 0 270)
			(layer "F.SilkS")
			(hide yes)
			(effects
				(font
					(size 1.27 1.27)
				)
			)
		)
		(property "Value" ""
			(at 0 0 270)
			(layer "F.Fab")
			(effects
				(font
					(size 1.27 1.27)
				)
			)
		)
		(duplicate_pad_numbers_are_jumpers no)
		(fp_line
			(start -0.7874 0.4064)
			(end -0.7874 -0.4064)
			(stroke
				(width 0.1524)
				(type default)
			)
			(layer "F.SilkS")
		)
		(fp_line
			(start 0.7874 0.4064)
			(end -0.7874 0.4064)
			(stroke
				(width 0.1524)
				(type default)
			)
			(layer "F.SilkS")
		)
		(fp_line
			(start -0.7874 -0.4064)
			(end 0.7874 -0.4064)
			(stroke
				(width 0.1524)
				(type default)
			)
			(layer "F.SilkS")
		)
		(fp_line
			(start 0.7874 -0.4064)
			(end 0.7874 0.4064)
			(stroke
				(width 0.1524)
				(type default)
			)
			(layer "F.SilkS")
		)
		(fp_line
			(start -0.67945 0.3048)
			(end -0.67945 -0.305054)
			(stroke
				(width 0.1)
				(type default)
			)
			(layer "F.Fab")
		)
		(fp_line
			(start -0.12065 0.3048)
			(end -0.67945 0.3048)
			(stroke
				(width 0.1)
				(type default)
			)
			(layer "F.Fab")
		)
		(fp_line
			(start 0.120396 0.3048)
			(end 0.120396 0.2794)
			(stroke
				(width 0.1)
				(type default)
			)
			(layer "F.Fab")
		)
		(fp_line
			(start 0.67945 0.3048)
			(end 0.120396 0.3048)
			(stroke
				(width 0.1)
				(type default)
			)
			(layer "F.Fab")
		)
		(fp_line
			(start -0.12065 0.2794)
			(end -0.12065 0.3048)
			(stroke
				(width 0.1)
				(type default)
			)
			(layer "F.Fab")
		)
		(fp_line
			(start 0.120396 0.2794)
			(end -0.12065 0.2794)
			(stroke
				(width 0.1)
				(type default)
			)
			(layer "F.Fab")
		)
		(fp_line
			(start -0.12065 -0.2794)
			(end 0.12065 -0.2794)
			(stroke
				(width 0.1)
				(type default)
			)
			(layer "F.Fab")
		)
		(fp_line
			(start 0.12065 -0.2794)
			(end 0.12065 -0.3048)
			(stroke
				(width 0.1)
				(type default)
			)
			(layer "F.Fab")
		)
		(fp_line
			(start 0.12065 -0.3048)
			(end 0.67945 -0.3048)
			(stroke
				(width 0.1)
				(type default)
			)
			(layer "F.Fab")
		)
		(fp_line
			(start 0.67945 -0.3048)
			(end 0.67945 0.3048)
			(stroke
				(width 0.1)
				(type default)
			)
			(layer "F.Fab")
		)
		(fp_line
			(start -0.67945 -0.305054)
			(end -0.12065 -0.305054)
			(stroke
				(width 0.1)
				(type default)
			)
			(layer "F.Fab")
		)
		(fp_line
			(start -0.12065 -0.305054)
			(end -0.12065 -0.2794)
			(stroke
				(width 0.1)
				(type default)
			)
			(layer "F.Fab")
		)
		(pad "1" smd circle
			(at -0.40005 0 270)
			(size 0 0)
			(layers "F.Cu" "F.Mask" "F.Paste")
			(net "HP_NIC1_PWRGD_R")
		)
		(pad "2" smd circle
			(at 0.40005 0 270)
			(size 0 0)
			(layers "F.Cu" "F.Mask" "F.Paste")
			(net "HP_NIC1_PWRGD")
		)
	)
)
